#ISCELL
  mstr_misc dns *
  *
#ISCELL
  pure_quanta quanta_title_block_c *
  *
#ISCELL
  pure_quanta_power cad_note *
  *
#CELL
  pure_quanta q_res *
  page349_i10
#ISCELL
  standard offpage *
  page349_i100
#ISCELL
  standard offpage *
  page349_i101
#ISCELL
  standard offpage *
  page349_i102
#ISCELL
  standard offpage *
  page349_i103
#ISCELL
  standard offpage *
  page349_i104
#ISCELL
  standard offpage *
  page349_i105
#ISCELL
  standard offpage *
  page349_i106
#ISCELL
  standard offpage *
  page349_i107
#ISCELL
  standard offpage *
  page349_i108
#ISCELL
  standard offpage *
  page349_i109
#ISCELL
  standard offpage *
  page349_i110
#ISCELL
  pure_quanta_power universal_gnd *
  page349_i111
#CELL
  pure_quanta q_cap *
  page349_i112
#CELL
  pure_quanta q_res *
  page349_i113
#ISCELL
  pure_quanta_power p1v0 *
  page349_i114
#CELL
  pure_quanta q_res *
  page349_i115
#CELL
  pure_quanta q_res *
  page349_i116
#ISCELL
  pure_quanta_power universal_gnd *
  page349_i117
#ISCELL
  pure_quanta_power universal_power *
  page349_i118
#CELL
  pure_quanta q_res *
  page349_i119
#CELL
  pure_quanta q_res *
  page349_i120
#CELL
  pure_quanta q_res *
  page349_i121
#CELL
  pure_quanta q_res *
  page349_i122
#CELL
  pure_quanta q_res *
  page349_i123
#CELL
  pure_quanta q_res *
  page349_i124
#CELL
  pure_quanta q_res *
  page349_i125
#CELL
  pure_quanta q_res *
  page349_i126
#CELL
  pure_quanta q_res *
  page349_i127
#CELL
  pure_quanta q_res *
  page349_i128
#CELL
  pure_quanta q_res *
  page349_i129
#ISCELL
  standard offpage *
  page349_i13
#CELL
  pure_quanta q_res *
  page349_i130
#CELL
  pure_quanta q_res *
  page349_i131
#CELL
  pure_quanta q_res *
  page349_i132
#CELL
  pure_quanta q_res *
  page349_i133
#CELL
  pure_quanta q_res *
  page349_i134
#CELL
  pure_quanta q_res *
  page349_i135
#CELL
  pure_quanta q_res *
  page349_i136
#CELL
  pure_quanta q_res *
  page349_i137
#CELL
  pure_quanta q_res *
  page349_i138
#ISCELL
  pure_quanta_power universal_power *
  page349_i139
#ISCELL
  standard offpage *
  page349_i14
#ISCELL
  standard offpage *
  page349_i140
#ISCELL
  standard offpage *
  page349_i141
#CELL
  pure_quanta q_res *
  page349_i142
#ISCELL
  pure_quanta_power gnd *
  page349_i143
#CELL
  pure_quanta q_res *
  page349_i144
#CELL
  pure_quanta q_res *
  page349_i145
#ISCELL
  pure_quanta_power vcc_core *
  page349_i146
#CELL
  pure_quanta q_res *
  page349_i147
#CELL
  pure_quanta conn4_hfk1040l0p1l7h *
  page349_i148
#CELL
  pure_quanta q_res *
  page349_i149
#ISCELL
  standard offpage *
  page349_i15
#CELL
  pure_quanta q_res *
  page349_i150
#CELL
  pure_quanta q_res *
  page349_i151
#ISCELL
  standard offpage *
  page349_i152
#ISCELL
  standard offpage *
  page349_i153
#ISCELL
  standard offpage *
  page349_i156
#ISCELL
  standard offpage *
  page349_i157
#CELL
  pure_quanta q_res *
  page349_i158
#CELL
  pure_quanta q_res *
  page349_i159
#ISCELL
  standard offpage *
  page349_i16
#ISCELL
  standard offpage *
  page349_i160
#CELL
  pure_quanta q_res *
  page349_i161
#CELL
  pure_quanta q_res *
  page349_i17
#CELL
  pure_quanta q_res *
  page349_i172
#CELL
  pure_quanta q_res *
  page349_i173
#ISCELL
  standard offpage *
  page349_i174
#ISCELL
  standard offpage *
  page349_i175
#CELL
  pure_quanta q_res *
  page349_i176
#ISCELL
  standard offpage *
  page349_i177
#ISCELL
  standard offpage *
  page349_i178
#ISCELL
  standard offpage *
  page349_i179
#CELL
  pure_quanta q_res *
  page349_i18
#ISCELL
  standard offpage *
  page349_i180
#CELL
  pure_quanta q_res *
  page349_i181
#CELL
  pure_quanta q_res *
  page349_i182
#CELL
  pure_quanta q_res *
  page349_i183
#CELL
  pure_quanta q_res *
  page349_i184
#CELL
  pure_quanta q_res *
  page349_i185
#CELL
  pure_quanta q_res *
  page349_i186
#CELL
  pure_quanta q_res *
  page349_i187
#ISCELL
  standard offpage *
  page349_i188
#ISCELL
  standard offpage *
  page349_i189
#ISCELL
  standard offpage *
  page349_i19
#ISCELL
  standard offpage *
  page349_i190
#ISCELL
  standard offpage *
  page349_i191
#ISCELL
  standard offpage *
  page349_i194
#ISCELL
  standard offpage *
  page349_i195
#CELL
  pure_quanta q_res *
  page349_i198
#CELL
  pure_quanta q_res *
  page349_i199
#CELL
  pure_quanta q_res *
  page349_i20
#ISCELL
  standard offpage *
  page349_i200
#ISCELL
  standard offpage *
  page349_i201
#ISCELL
  standard offpage *
  page349_i204
#ISCELL
  standard offpage *
  page349_i205
#CELL
  pure_quanta q_res *
  page349_i206
#CELL
  pure_quanta q_res *
  page349_i207
#ISCELL
  standard offpage *
  page349_i208
#ISCELL
  standard offpage *
  page349_i209
#CELL
  pure_quanta q_res *
  page349_i21
#ISCELL
  standard offpage *
  page349_i212
#ISCELL
  standard offpage *
  page349_i213
#ISCELL
  standard offpage *
  page349_i214
#ISCELL
  standard offpage *
  page349_i215
#CELL
  pure_quanta q_res *
  page349_i218
#CELL
  pure_quanta q_res *
  page349_i219
#CELL
  pure_quanta q_res *
  page349_i22
#CELL
  pure_quanta q_res *
  page349_i220
#CELL
  pure_quanta q_res *
  page349_i221
#CELL
  pure_quanta q_res *
  page349_i222
#CELL
  pure_quanta q_res *
  page349_i223
#CELL
  pure_quanta q_res *
  page349_i224
#CELL
  pure_quanta q_res *
  page349_i225
#CELL
  pure_quanta q_res *
  page349_i226
#CELL
  pure_quanta q_res *
  page349_i227
#CELL
  pure_quanta q_res *
  page349_i228
#CELL
  pure_quanta q_res *
  page349_i229
#CELL
  pure_quanta q_res *
  page349_i23
#CELL
  pure_quanta q_res *
  page349_i231
#CELL
  pure_quanta q_res *
  page349_i24
#CELL
  pure_quanta q_res *
  page349_i25
#ISCELL
  pure_quanta_power universal_power *
  page349_i26
#CELL
  pure_quanta q_res *
  page349_i27
#CELL
  pure_quanta q_res *
  page349_i28
#CELL
  pure_quanta q_res *
  page349_i29
#ISCELL
  standard offpage *
  page349_i3
#CELL
  pure_quanta q_res *
  page349_i30
#ISCELL
  pure_quanta_power universal_power *
  page349_i31
#CELL
  pure_quanta q_res *
  page349_i32
#ISCELL
  standard offpage *
  page349_i33
#ISCELL
  standard offpage *
  page349_i34
#ISCELL
  standard offpage *
  page349_i35
#ISCELL
  standard offpage *
  page349_i36
#ISCELL
  standard offpage *
  page349_i37
#ISCELL
  standard offpage *
  page349_i38
#ISCELL
  standard offpage *
  page349_i39
#ISCELL
  standard offpage *
  page349_i4
#ISCELL
  standard offpage *
  page349_i40
#ISCELL
  standard offpage *
  page349_i41
#ISCELL
  standard offpage *
  page349_i42
#ISCELL
  pure_quanta_power universal_power *
  page349_i43
#ISCELL
  pure_quanta_power universal_gnd *
  page349_i44
#ISCELL
  pure_quanta_power vcc_core *
  page349_i46
#ISCELL
  standard offpage *
  page349_i47
#CELL
  pure_quanta q_res *
  page349_i48
#CELL
  pure_quanta q_res *
  page349_i49
#ISCELL
  standard offpage *
  page349_i50
#ISCELL
  standard offpage *
  page349_i51
#ISCELL
  standard offpage *
  page349_i54
#ISCELL
  standard offpage *
  page349_i55
#CELL
  pure_quanta q_res *
  page349_i56
#CELL
  pure_quanta q_res *
  page349_i57
#ISCELL
  standard offpage *
  page349_i58
#ISCELL
  standard offpage *
  page349_i59
#ISCELL
  standard offpage *
  page349_i60
#ISCELL
  standard offpage *
  page349_i61
#ISCELL
  standard offpage *
  page349_i64
#ISCELL
  standard offpage *
  page349_i65
#ISCELL
  pure_quanta_power universal_gnd *
  page349_i66
#ISCELL
  standard offpage *
  page349_i67
#ISCELL
  standard offpage *
  page349_i68
#CELL
  pure_quanta q_cap *
  page349_i69
#ISCELL
  standard offpage *
  page349_i70
#ISCELL
  standard offpage *
  page349_i71
#ISCELL
  standard offpage *
  page349_i72
#ISCELL
  standard offpage *
  page349_i73
#ISCELL
  standard offpage *
  page349_i74
#ISCELL
  standard offpage *
  page349_i75
#ISCELL
  standard offpage *
  page349_i76
#ISCELL
  standard offpage *
  page349_i77
#ISCELL
  standard offpage *
  page349_i78
#ISCELL
  standard offpage *
  page349_i79
#ISCELL
  standard offpage *
  page349_i80
#CELL
  pure_quanta q_res *
  page349_i81
#CELL
  pure_quanta q_res *
  page349_i82
#CELL
  pure_quanta q_res *
  page349_i83
#CELL
  pure_quanta q_res *
  page349_i84
#ISCELL
  standard offpage *
  page349_i85
#ISCELL
  standard offpage *
  page349_i86
#ISCELL
  standard offpage *
  page349_i87
#ISCELL
  standard offpage *
  page349_i88
#CELL
  pure_quanta q_res *
  page349_i89
#CELL
  pure_quanta q_res *
  page349_i9
#CELL
  pure_quanta q_res *
  page349_i90
#CELL
  pure_quanta q_res *
  page349_i91
#CELL
  pure_quanta q_res *
  page349_i92
#ISCELL
  standard offpage *
  page349_i93
#ISCELL
  standard offpage *
  page349_i94
#ISCELL
  standard offpage *
  page349_i95
#ISCELL
  standard offpage *
  page349_i96
#ISCELL
  standard offpage *
  page349_i97
#ISCELL
  standard offpage *
  page349_i98
#ISCELL
  standard offpage *
  page349_i99
